(kicad_pcb
	(version 20260206)
	(generator "pcbnew")
	(generator_version "10.0")
	(general
		(thickness 1.6)
		(legacy_teardrops no)
	)
	(paper "A4")
	(title_block
		(title "Wiwynn_Tioga_Pass_MB.brd")
		(comment 1 "Tioga Pass / footprints 521-525 of 4770")
	)
	(layers
		(0 "F.Cu" signal "TOP")
		(4 "In1.Cu" signal "L2GND")
		(6 "In2.Cu" signal "L3")
		(8 "In3.Cu" signal "L4GND")
		(10 "In4.Cu" signal "L5")
		(12 "In5.Cu" signal "L6GND")
		(14 "In6.Cu" signal "L7VCC")
		(16 "In7.Cu" signal "L8VCC")
		(18 "In8.Cu" signal "L9GND")
		(20 "In9.Cu" signal "L10")
		(22 "In10.Cu" signal "L11GND")
		(24 "In11.Cu" signal "L12")
		(26 "In12.Cu" signal "L13GND")
		(2 "B.Cu" signal "BOTTOM")
		(9 "F.Adhes" user "F.Adhesive")
		(11 "B.Adhes" user "B.Adhesive")
		(13 "F.Paste" user "Package Geometry/Pastemask Top")
		(15 "B.Paste" user "Package Geometry/Pastemask Bottom")
		(5 "F.SilkS" user "Ref Des/Silkscreen Top")
		(7 "B.SilkS" user "Ref Des/Silkscreen Bottom")
		(1 "F.Mask" user "Board Geometry/Soldermask Top")
		(3 "B.Mask" user "Board Geometry/Soldermask Bottom")
		(17 "Dwgs.User" user "User.Drawings")
		(19 "Cmts.User" user "User.Comments")
		(21 "Eco1.User" user "User.Eco1")
		(23 "Eco2.User" user "User.Eco2")
		(25 "Edge.Cuts" user "Board Geometry/Outline")
		(27 "Margin" user)
		(31 "F.CrtYd" user "Package Geometry/Place Bound Top")
		(29 "B.CrtYd" user "Package Geometry/Place Bound Bottom")
		(35 "F.Fab" user "Ref Des/Assembly Top")
		(33 "B.Fab" user "Ref Des/Assembly Bottom")
	)
	(footprint ""
		(layer "F.Cu")
		(at 23.114 -73.406 -90)
		(property "Reference" "R1D39"
			(at 0 0 270)
			(layer "F.SilkS")
			(hide yes)
			(effects
				(font
					(size 1.27 1.27)
				)
			)
		)
		(property "Value" ""
			(at 0 0 270)
			(layer "F.Fab")
			(effects
				(font
					(size 1.27 1.27)
				)
			)
		)
		(duplicate_pad_numbers_are_jumpers no)
		(fp_poly
			(pts
				(xy -0.2794 -0.1016) (xy 0.2794 -0.1016) (xy 0.2794 0.9906) (xy -0.2794 0.9906)
			)
			(stroke
				(width 0)
				(type default)
			)
			(fill no)
			(layer "F.CrtYd")
		)
		(fp_line
			(start -0.2794 0.9906)
			(end 0.2794 0.9906)
			(stroke
				(width 0.1)
				(type default)
			)
			(layer "F.Fab")
		)
		(fp_line
			(start 0.2794 0.9906)
			(end 0.2794 -0.1016)
			(stroke
				(width 0.1)
				(type default)
			)
			(layer "F.Fab")
		)
		(fp_line
			(start -0.2794 -0.1016)
			(end -0.2794 0.9906)
			(stroke
				(width 0.1)
				(type default)
			)
			(layer "F.Fab")
		)
		(fp_line
			(start 0.2794 -0.1016)
			(end -0.2794 -0.1016)
			(stroke
				(width 0.1)
				(type default)
			)
			(layer "F.Fab")
		)
		(pad "1" smd rect
			(at 0 0 270)
			(size 0.508 0.508)
			(layers "F.Cu" "F.Mask" "F.Paste")
			(net "A_HSC_VCAP")
		)
		(pad "2" smd rect
			(at 0 0.889 270)
			(size 0.508 0.508)
			(layers "F.Cu" "F.Mask" "F.Paste")
			(net "A_HSC_PSET")
		)
		(zone
			(layer "F.Cu")
			(hatch none 0.5)
			(connect_pads
				(clearance 0)
			)
			(min_thickness 0.25)
			(keepout
				(tracks not_allowed)
				(vias allowed)
				(pads allowed)
				(copperpour not_allowed)
				(footprints allowed)
			)
			(placement
				(enabled no)
				(sheetname "")
			)
			(fill
				(thermal_gap 0.5)
				(thermal_bridge_width 0.5)
				(island_removal_mode 0)
			)
			(polygon
				(pts
					(xy 22.479 -73.66) (xy 22.479 -73.152) (xy 22.86 -73.152) (xy 22.86 -73.66)
				)
			)
		)
		(zone
			(layer "F.Cu")
			(hatch none 0.5)
			(connect_pads
				(clearance 0)
			)
			(min_thickness 0.25)
			(keepout
				(tracks allowed)
				(vias not_allowed)
				(pads allowed)
				(copperpour not_allowed)
				(footprints allowed)
			)
			(placement
				(enabled no)
				(sheetname "")
			)
			(fill
				(thermal_gap 0.5)
				(thermal_bridge_width 0.5)
				(island_removal_mode 0)
			)
			(polygon
				(pts
					(xy 22.86 -73.66) (xy 22.86 -73.152) (xy 22.479 -73.152) (xy 22.479 -73.66)
				)
			)
		)
	)
	(footprint ""
		(layer "F.Cu")
		(at 332.888844 -117.35562 -90)
		(property "Reference" "C843"
			(at -0.8382 -0.67818 270)
			(unlocked yes)
			(layer "F.SilkS")
			(effects
				(font
					(size 0.4064 0.254)
					(thickness 0.1524)
				)
				(justify left)
			)
		)
		(property "Value" ""
			(at 0 0 270)
			(layer "F.Fab")
			(effects
				(font
					(size 1.27 1.27)
				)
			)
		)
		(duplicate_pad_numbers_are_jumpers no)
		(fp_poly
			(pts
				(xy 0.3048 -0.1016) (xy 0.3048 0.9906) (xy -0.3048 0.9906) (xy -0.3048 -0.1016)
			)
			(stroke
				(width 0)
				(type default)
			)
			(fill no)
			(layer "F.CrtYd")
		)
		(fp_line
			(start -0.3048 0.9906)
			(end 0.3048 0.9906)
			(stroke
				(width 0.1)
				(type default)
			)
			(layer "F.Fab")
		)
		(fp_line
			(start 0.3048 0.9906)
			(end 0.3048 -0.1016)
			(stroke
				(width 0.1)
				(type default)
			)
			(layer "F.Fab")
		)
		(fp_line
			(start -0.3048 -0.1016)
			(end -0.3048 0.9906)
			(stroke
				(width 0.1)
				(type default)
			)
			(layer "F.Fab")
		)
		(fp_line
			(start 0.3048 -0.1016)
			(end -0.3048 -0.1016)
			(stroke
				(width 0.1)
				(type default)
			)
			(layer "F.Fab")
		)
		(pad "1" smd rect
			(at 0 0 270)
			(size 0.508 0.508)
			(layers "F.Cu" "F.Mask" "F.Paste")
			(net "P3E_CPU0_PE1_PCH_TXP<8>")
		)
		(pad "2" smd rect
			(at 0 0.889 270)
			(size 0.508 0.508)
			(layers "F.Cu" "F.Mask" "F.Paste")
			(net "P3E_CPU0_PE1_PCH_CON_TXP<8>")
		)
		(zone
			(layer "F.Cu")
			(hatch none 0.5)
			(connect_pads
				(clearance 0)
			)
			(min_thickness 0.25)
			(keepout
				(tracks not_allowed)
				(vias allowed)
				(pads allowed)
				(copperpour not_allowed)
				(footprints allowed)
			)
			(placement
				(enabled no)
				(sheetname "")
			)
			(fill
				(thermal_gap 0.5)
				(thermal_bridge_width 0.5)
				(island_removal_mode 0)
			)
			(polygon
				(pts
					(xy 332.253844 -117.60962) (xy 332.253844 -117.10162) (xy 332.634844 -117.10162) (xy 332.634844 -117.60962)
				)
			)
		)
		(zone
			(layer "F.Cu")
			(hatch none 0.5)
			(connect_pads
				(clearance 0)
			)
			(min_thickness 0.25)
			(keepout
				(tracks allowed)
				(vias not_allowed)
				(pads allowed)
				(copperpour not_allowed)
				(footprints allowed)
			)
			(placement
				(enabled no)
				(sheetname "")
			)
			(fill
				(thermal_gap 0.5)
				(thermal_bridge_width 0.5)
				(island_removal_mode 0)
			)
			(polygon
				(pts
					(xy 332.634844 -117.60962) (xy 332.634844 -117.10162) (xy 332.253844 -117.10162) (xy 332.253844 -117.60962)
				)
			)
		)
	)
	(footprint ""
		(layer "F.Cu")
		(at 0.74676 -11.99896)
		(property "Reference" "RT19"
			(at 1.01473 0.656336 270)
			(unlocked yes)
			(layer "F.SilkS")
			(effects
				(font
					(size 0.4064 0.254)
					(thickness 0.1524)
				)
			)
		)
		(property "Value" ""
			(at 0 0 0)
			(layer "F.Fab")
			(effects
				(font
					(size 1.27 1.27)
				)
			)
		)
		(duplicate_pad_numbers_are_jumpers no)
		(fp_rect
			(start -0.4953 1.6002)
			(end 0.4953 -0.2032)
			(stroke
				(width 0)
				(type default)
			)
			(fill no)
			(layer "F.CrtYd")
		)
		(fp_line
			(start -0.4953 -0.2032)
			(end 0.4953 -0.2032)
			(stroke
				(width 0.1)
				(type default)
			)
			(layer "F.Fab")
		)
		(fp_line
			(start -0.4953 1.6002)
			(end -0.4953 -0.2032)
			(stroke
				(width 0.1)
				(type default)
			)
			(layer "F.Fab")
		)
		(fp_line
			(start 0.4953 -0.2032)
			(end 0.4953 1.6002)
			(stroke
				(width 0.1)
				(type default)
			)
			(layer "F.Fab")
		)
		(fp_line
			(start 0.4953 1.6002)
			(end -0.4953 1.6002)
			(stroke
				(width 0.1)
				(type default)
			)
			(layer "F.Fab")
		)
		(pad "1" smd rect
			(at 0 0)
			(size 0.762 0.889)
			(layers "F.Cu" "F.Mask" "F.Paste")
			(net "VR_PVDDQ_GHJ_PH1_BOOT")
		)
		(pad "2" smd rect
			(at 0 1.397)
			(size 0.762 0.889)
			(layers "F.Cu" "F.Mask" "F.Paste")
			(net "VR_PVDDQ_GHJ_PH1_BOOT_R")
		)
		(zone
			(layer "F.Cu")
			(hatch none 0.5)
			(connect_pads
				(clearance 0)
			)
			(min_thickness 0.25)
			(keepout
				(tracks not_allowed)
				(vias allowed)
				(pads allowed)
				(copperpour not_allowed)
				(footprints allowed)
			)
			(placement
				(enabled no)
				(sheetname "")
			)
			(fill
				(thermal_gap 0.5)
				(thermal_bridge_width 0.5)
				(island_removal_mode 0)
			)
			(polygon
				(pts
					(xy 0.36576 -11.04646) (xy 1.12776 -11.04646) (xy 1.12776 -11.55446) (xy 0.36576 -11.55446)
				)
			)
		)
		(zone
			(layer "F.Cu")
			(hatch none 0.5)
			(connect_pads
				(clearance 0)
			)
			(min_thickness 0.25)
			(keepout
				(tracks allowed)
				(vias not_allowed)
				(pads allowed)
				(copperpour not_allowed)
				(footprints allowed)
			)
			(placement
				(enabled no)
				(sheetname "")
			)
			(fill
				(thermal_gap 0.5)
				(thermal_bridge_width 0.5)
				(island_removal_mode 0)
			)
			(polygon
				(pts
					(xy 0.36576 -11.04646) (xy 1.12776 -11.04646) (xy 1.12776 -11.55446) (xy 0.36576 -11.55446)
				)
			)
		)
	)
	(footprint ""
		(layer "F.Cu")
		(at 411.0355 -111.633 -90)
		(property "Reference" "R8C1"
			(at 0 0 270)
			(layer "F.SilkS")
			(hide yes)
			(effects
				(font
					(size 1.27 1.27)
				)
			)
		)
		(property "Value" ""
			(at 0 0 270)
			(layer "F.Fab")
			(effects
				(font
					(size 1.27 1.27)
				)
			)
		)
		(duplicate_pad_numbers_are_jumpers no)
		(fp_poly
			(pts
				(xy -0.2794 -0.1016) (xy 0.2794 -0.1016) (xy 0.2794 0.9906) (xy -0.2794 0.9906)
			)
			(stroke
				(width 0)
				(type default)
			)
			(fill no)
			(layer "F.CrtYd")
		)
		(fp_line
			(start -0.2794 0.9906)
			(end 0.2794 0.9906)
			(stroke
				(width 0.1)
				(type default)
			)
			(layer "F.Fab")
		)
		(fp_line
			(start 0.2794 0.9906)
			(end 0.2794 -0.1016)
			(stroke
				(width 0.1)
				(type default)
			)
			(layer "F.Fab")
		)
		(fp_line
			(start -0.2794 -0.1016)
			(end -0.2794 0.9906)
			(stroke
				(width 0.1)
				(type default)
			)
			(layer "F.Fab")
		)
		(fp_line
			(start 0.2794 -0.1016)
			(end -0.2794 -0.1016)
			(stroke
				(width 0.1)
				(type default)
			)
			(layer "F.Fab")
		)
		(pad "1" smd rect
			(at 0 0 270)
			(size 0.508 0.508)
			(layers "F.Cu" "F.Mask" "F.Paste")
			(net "P3V3_STBY")
		)
		(pad "2" smd rect
			(at 0 0.889 270)
			(size 0.508 0.508)
			(layers "F.Cu" "F.Mask" "F.Paste")
			(net "FM_SLT_CFG1")
		)
		(zone
			(layer "F.Cu")
			(hatch none 0.5)
			(connect_pads
				(clearance 0)
			)
			(min_thickness 0.25)
			(keepout
				(tracks not_allowed)
				(vias allowed)
				(pads allowed)
				(copperpour not_allowed)
				(footprints allowed)
			)
			(placement
				(enabled no)
				(sheetname "")
			)
			(fill
				(thermal_gap 0.5)
				(thermal_bridge_width 0.5)
				(island_removal_mode 0)
			)
			(polygon
				(pts
					(xy 410.4005 -111.887) (xy 410.4005 -111.379) (xy 410.7815 -111.379) (xy 410.7815 -111.887)
				)
			)
		)
		(zone
			(layer "F.Cu")
			(hatch none 0.5)
			(connect_pads
				(clearance 0)
			)
			(min_thickness 0.25)
			(keepout
				(tracks allowed)
				(vias not_allowed)
				(pads allowed)
				(copperpour not_allowed)
				(footprints allowed)
			)
			(placement
				(enabled no)
				(sheetname "")
			)
			(fill
				(thermal_gap 0.5)
				(thermal_bridge_width 0.5)
				(island_removal_mode 0)
			)
			(polygon
				(pts
					(xy 410.7815 -111.887) (xy 410.7815 -111.379) (xy 410.4005 -111.379) (xy 410.4005 -111.887)
				)
			)
		)
	)
	(footprint ""
		(layer "F.Cu")
		(at 410.340048 -66.529966)
		(property "Reference" "J8E1"
			(at 0.762 9.42213 180)
			(unlocked yes)
			(layer "F.SilkS")
			(effects
				(font
					(size 0.7874 0.5842)
					(thickness 0.1524)
				)
			)
		)
		(property "Value" ""
			(at 0 0 0)
			(layer "F.Fab")
			(effects
				(font
					(size 1.27 1.27)
				)
			)
		)
		(duplicate_pad_numbers_are_jumpers no)
		(fp_poly
			(pts
				(xy -1.048512 -0.391414) (xy -1.587246 -1.648714) (xy -2.305558 -0.930402)
			)
			(stroke
				(width 0)
				(type default)
			)
			(fill yes)
			(layer "F.SilkS")
		)
		(fp_rect
			(start -0.4572 7.72922)
			(end 4.6736 -2.71018)
			(stroke
				(width 0)
				(type default)
			)
			(fill no)
			(layer "F.CrtYd")
		)
		(fp_line
			(start -0.4572 -2.71018)
			(end -0.4572 7.72922)
			(stroke
				(width 0.1)
				(type default)
			)
			(layer "F.Fab")
		)
		(fp_line
			(start -0.4572 7.72922)
			(end 4.6736 7.72922)
			(stroke
				(width 0.1)
				(type default)
			)
			(layer "F.Fab")
		)
		(fp_line
			(start 4.6736 -2.71018)
			(end -0.4572 -2.71018)
			(stroke
				(width 0.1)
				(type default)
			)
			(layer "F.Fab")
		)
		(fp_line
			(start 4.6736 7.72922)
			(end 4.6736 -2.71018)
			(stroke
				(width 0.1)
				(type default)
			)
			(layer "F.Fab")
		)
		(fp_poly
			(pts
				(xy -1.215644 -0.006858) (xy -2.485644 0.501142) (xy -2.485644 -0.514858)
			)
			(stroke
				(width 0)
				(type default)
			)
			(fill yes)
			(layer "F.Fab")
		)
		(fp_text user "6"
			(at -1.763776 5.710682 0)
			(unlocked yes)
			(layer "F.SilkS")
			(effects
				(font
					(size 0.7874 0.5842)
					(thickness 0.1524)
				)
				(justify left)
			)
		)
		(fp_text user "7"
			(at 5.340604 1.199642 0)
			(unlocked yes)
			(layer "F.SilkS")
			(effects
				(font
					(size 0.7874 0.5842)
					(thickness 0.1524)
				)
				(justify left)
			)
		)
		(fp_text user "11"
			(at 5.407152 6.367018 0)
			(unlocked yes)
			(layer "F.SilkS")
			(effects
				(font
					(size 0.7874 0.5842)
					(thickness 0.1524)
				)
				(justify left)
			)
		)
		(fp_text user "6"
			(at -2.42951 4.930394 0)
			(unlocked yes)
			(layer "F.Fab")
			(effects
				(font
					(size 0.7874 0.5842)
					(thickness 0.1524)
				)
				(justify left)
			)
		)
		(fp_text user "11"
			(at 5.280152 4.716018 0)
			(unlocked yes)
			(layer "F.Fab")
			(effects
				(font
					(size 0.7874 0.5842)
					(thickness 0.1524)
				)
				(justify left)
			)
		)
		(fp_text user "7"
			(at 6.282944 0.5588 0)
			(unlocked yes)
			(layer "F.Fab")
			(effects
				(font
					(size 0.7874 0.5842)
					(thickness 0.1524)
				)
				(justify left)
			)
		)
		(pad "" np_thru_hole circle
			(at 3.20802 -0.52578)
			(size 0.254 0.254)
			(drill 0.762)
			(layers "*.Cu" "*.Mask")
			(clearance 0.5715)
			(thermal_gap 0.5715)
		)
		(pad "" np_thru_hole circle
			(at 3.20802 5.51942)
			(size 0.254 0.254)
			(drill 0.762)
			(layers "*.Cu" "*.Mask")
			(clearance 0.5715)
			(thermal_gap 0.5715)
		)
		(pad "1" smd rect
			(at 0 0)
			(size 1.6256 0.6096)
			(layers "F.Cu" "F.Mask" "F.Paste")
			(net "SPI_PCH_TPM_CLK_R")
		)
		(pad "2" smd rect
			(at 0 0.999998)
			(size 1.6256 0.6096)
			(layers "F.Cu" "F.Mask" "F.Paste")
			(net "RST_PLTRST_BUF_N")
		)
		(pad "3" smd rect
			(at 0 1.999996)
			(size 1.6256 0.6096)
			(layers "F.Cu" "F.Mask" "F.Paste")
			(net "SPI_PCH_TPM_MOSI_R")
		)
		(pad "4" smd rect
			(at 0 2.999994)
			(size 1.6256 0.6096)
			(layers "F.Cu" "F.Mask" "F.Paste")
			(net "SPI_PCH_TPM_MISO_R")
		)
		(pad "5" smd rect
			(at 0 3.999992)
			(size 1.6256 0.6096)
			(layers "F.Cu" "F.Mask" "F.Paste")
			(net "SPI_PCH_TPM_CS_R_N")
		)
		(pad "6" smd rect
			(at 0 4.99999)
			(size 1.6256 0.6096)
			(layers "F.Cu" "F.Mask" "F.Paste")
			(net "SMB_SENSOR_STBY_LVC3_SDA")
		)
		(pad "7" smd rect
			(at 4.2164 0.499872)
			(size 1.6256 0.6096)
			(layers "F.Cu" "F.Mask" "F.Paste")
			(net "P3V3_STBY")
		)
		(pad "8" smd rect
			(at 4.2164 1.49987)
			(size 1.6256 0.6096)
			(layers "F.Cu" "F.Mask" "F.Paste")
			(net "FM_TPM_PRES_RST_N")
		)
		(pad "9" smd rect
			(at 4.2164 2.499868)
			(size 1.6256 0.6096)
			(layers "F.Cu" "F.Mask" "F.Paste")
			(net "IRQ_SPI_TPM_N_R")
		)
		(pad "10" smd rect
			(at 4.2164 3.499866)
			(size 1.6256 0.6096)
			(layers "F.Cu" "F.Mask" "F.Paste")
			(net "SMB_SENSOR_STBY_LVC3_SCL")
		)
		(pad "11" smd rect
			(at 4.2164 4.499864)
			(size 1.6256 0.6096)
			(layers "F.Cu" "F.Mask" "F.Paste")
			(net "GND")
		)
		(pad "MP1" smd custom
			(at 2.1082 -1.71958)
			(size 0.34925 0.34925)
			(layers "F.Cu" "F.Mask" "F.Paste")
			(net "GND")
			(options
				(clearance outline)
				(anchor circle)
			)
			(primitives
				(gr_poly
					(pts
						(arc
							(start 1.49733 0.6985)
							(mid 1.09982 0.558768)
							(end 0.70231 0.6985)
						)
						(xy -2.921 0.6985) (xy -2.921 -0.6985) (xy 2.921 -0.6985) (xy 2.921 0.6985)
					)
					(width 0)
					(fill yes)
				)
			)
		)
		(pad "MP2" smd custom
			(at 2.00406 6.800596)
			(size 0.34925 0.34925)
			(layers "F.Cu" "F.Mask" "F.Paste")
			(net "GND")
			(options
				(clearance outline)
				(anchor circle)
			)
			(primitives
				(gr_poly
					(pts
						(arc
							(start 1.49733 -0.6985)
							(mid 1.09982 -0.558768)
							(end 0.70231 -0.6985)
						)
						(xy -2.921 -0.6985) (xy -2.921 0.6985) (xy 2.921 0.6985) (xy 2.921 -0.6985)
					)
					(width 0)
					(fill yes)
				)
			)
		)
		(zone
			(layers "F.Cu" "B.Cu" "In1.Cu" "In2.Cu" "In3.Cu" "In4.Cu" "In5.Cu" "In6.Cu"
				"In7.Cu" "In8.Cu" "In9.Cu" "In10.Cu" "In11.Cu" "In12.Cu"
			)
			(hatch none 0.5)
			(connect_pads
				(clearance 0)
			)
			(min_thickness 0.25)
			(keepout
				(tracks not_allowed)
				(vias allowed)
				(pads allowed)
				(copperpour not_allowed)
				(footprints allowed)
			)
			(placement
				(enabled no)
				(sheetname "")
			)
			(fill
				(thermal_gap 0.5)
				(thermal_bridge_width 0.5)
				(island_removal_mode 0)
			)
			(polygon
				(pts
					(arc
						(start 414.246568 -67.055746)
						(mid 412.849568 -67.055746)
						(end 414.246568 -67.055746)
					)
				)
			)
		)
		(zone
			(layers "F.Cu" "B.Cu" "In1.Cu" "In2.Cu" "In3.Cu" "In4.Cu" "In5.Cu" "In6.Cu"
				"In7.Cu" "In8.Cu" "In9.Cu" "In10.Cu" "In11.Cu" "In12.Cu"
			)
			(hatch none 0.5)
			(connect_pads
				(clearance 0)
			)
			(min_thickness 0.25)
			(keepout
				(tracks not_allowed)
				(vias allowed)
				(pads allowed)
				(copperpour not_allowed)
				(footprints allowed)
			)
			(placement
				(enabled no)
				(sheetname "")
			)
			(fill
				(thermal_gap 0.5)
				(thermal_bridge_width 0.5)
				(island_removal_mode 0)
			)
			(polygon
				(pts
					(arc
						(start 414.246568 -61.010546)
						(mid 412.849568 -61.010546)
						(end 414.246568 -61.010546)
					)
				)
			)
		)
	)
)
